FILE_TYPE = CONNECTIVITY;
{Allegro Design Entry HDL 16.6-p007 (v16-6-112F) 10/10/2012}
"PAGE_NUMBER" = 90;
0"NC";
1"GND\g";
2"PVCCIO_CPU0\g";
3"GND\g";
4"PVCCIO_CPU0\g";
5"PVCCIO_CPU1\g";
6"PVCCIO_CPU1\g";
7"GND\g";
8"GND\g";
9"PD_CPU0_TEST12";
10"PD_CPU1_TEST12";
11"PD_CPU1_TEST13";
12"PD_CPU1_TEST14";
13"PD_CPU0_DMIMODE_OVERRIDE";
14"PU_CPU0_SOCKET_ID_1";
15"PU_CPU0_SOCKET_ID_0";
16"PD_CPU0_KSFC_DIS";
17"PD_CPU0_BIST_ENABLE";
18"PD_CPU0_TXT_PLTEN";
19"PU_CPU1_SOCKET_ID_0";
20"PU_CPU1_SOCKET_ID_1";
21"PD_CPU1_BIST_ENABLE";
22"PD_CPU1_KSFC_DIS";
23"PD_CPU1_DMIMODE_OVERRIDE";
24"PD_CPU1_TXT_PLTEN";
25"PU_CPU0_FRMAGENT";
26"H_CPU0_BMCINIT";
27"PD_CPU0_TEST13";
28"PU_CPU0_LEGACY_SKT";
29"PU_CPU0_TXT_AGENT";
30"PD_CPU0_TEST14";
31"PU_CPU0_EAR_N";
32"PU_CPU0_SAFE_MODE_BOOT";
33"PU_CPU1_EAR_N";
34"PU_CPU1_SAFE_MODE_BOOT";
35"H_CPU1_BMCINIT";
36"PU_CPU1_TXT_AGENT";
37"PU_CPU1_LEGACY_SKT";
38"PU_CPU1_FRMAGENT";
%"RES"
"1","(-325,1275)","0","mstr_discrete","I11";
;
CDS_SEC"1"
ROOM"PROC_SIDEBAND"
SEC"1"
SEC_TYPE"0402"
BOM_COST"PROC"
CDS_LIB"mstr_discrete"
CDS_LOCATION"R3D12"
WATTAGE"1/16W"
MATERIAL"CHIP"
TOLERANCE"1.0%"
PACK_TYPE"0402"
VALUE"240"
PART_NUMBER"G21796-294"
LOCATION"R3D12";
"B"
$PN"2"24;
"A"
$PN"1"1;
%"RES"
"1","(-325,1050)","0","mstr_discrete","I12";
;
CDS_SEC"1"
ROOM"PROC_SIDEBAND"
SEC"1"
SEC_TYPE"0402"
BOM_COST"PROC"
CDS_LIB"mstr_discrete"
CDS_LOCATION"R3D13"
MATERIAL"EMPTY"
WATTAGE"1/16W"
TOLERANCE"1.0%"
VALUE"240"
LOCATION"R3D13"
PACK_TYPE"0402"
PART_NUMBER"G21796-294";
"B"
$PN"2"21;
"A"
$PN"1"1;
%"RES"
"1","(-2450,1875)","0","mstr_discrete","I17";
;
CDS_SEC"1"
SEC_TYPE"0402"
SEC"1"
ROOM"PROC_SIDEBAND"
CDS_LIB"mstr_discrete"
BOM_COST"PROC"
CDS_LOCATION"R3D22"
WATTAGE"1/16W"
MATERIAL"EMPTY"
TOLERANCE"1.0%"
PACK_TYPE"0402"
VALUE"240"
PART_NUMBER"G21796-294"
LOCATION"R3D22";
"B"
$PN"2"38;
"A"
$PN"1"5;
%"GND"
"1","(-725,525)","0","mstr_symbols","I18";
;
HDL_POWER"GND"
CDS_LIB"mstr_symbols"
VOLTAGE"0"
BODY_TYPE"PLUMBING"
SIZE"1B";
"A\NAC"1;
%"RES"
"1","(-2450,1675)","0","mstr_discrete","I24";
;
CDS_SEC"1"
ROOM"PROC_SIDEBAND"
SEC_TYPE"0402"
SEC"1"
CDS_LIB"mstr_discrete"
BOM_COST"PROC"
CDS_LOCATION"R3D16"
WATTAGE"1/16W"
MATERIAL"EMPTY"
TOLERANCE"1.0%"
PACK_TYPE"0402"
VALUE"240"
PART_NUMBER"G21796-294"
LOCATION"R3D16";
"B"
$PN"2"35;
"A"
$PN"1"5;
%"RES"
"1","(-2450,1475)","0","mstr_discrete","I25";
;
ROOM"PROC_SIDEBAND"
$SEC"1"
CDS_SEC"1"
CDS_LIB"mstr_discrete"
BOM_COST"PROC"
CDS_LOCATION"R3D23"
WATTAGE"1/16W"
TOLERANCE"1.0%"
VALUE"240"
MATERIAL"EMPTY"
PACK_TYPE"0402"
PART_NUMBER"G21796-294"
LOCATION"R3D23";
"B"
$PN"2"36;
"A"
$PN"1"5;
%"RES"
"1","(-2425,1275)","0","mstr_discrete","I28";
;
CDS_SEC"1"
ROOM"PROC_SIDEBAND"
SEC"1"
SEC_TYPE"0402"
CDS_LIB"mstr_discrete"
BOM_COST"PROC"
CDS_LOCATION"R3D26"
WATTAGE"1/16W"
MATERIAL"EMPTY"
PACK_TYPE"0402"
TOLERANCE"1.0%"
VALUE"240"
PART_NUMBER"G21796-294"
LOCATION"R3D26";
"B"
$PN"2"34;
"A"
$PN"1"5;
%"RES"
"1","(-2475,4400)","0","mstr_discrete","I29";
;
CDS_SEC"1"
SEC"1"
SEC_TYPE"0402"
ROOM"PROC_SIDEBAND"
CDS_LIB"mstr_discrete"
BOM_COST"PROC"
CDS_LOCATION"R5D3"
WATTAGE"1/16W"
MATERIAL"CHIP"
TOLERANCE"1.0%"
VALUE"240"
PACK_TYPE"0402"
PART_NUMBER"G21796-294"
LOCATION"R5D3";
"B"
$PN"2"25;
"A"
$PN"1"2;
%"RES"
"1","(-500,3400)","0","mstr_discrete","I3";
;
CDS_SEC"1"
ROOM"PROC_SIDEBAND"
BOM_COST"PROC"
CDS_LIB"mstr_discrete"
SEC"1"
SEC_TYPE"0402"
CDS_LOCATION"R6D6"
MATERIAL"CHIP"
PACK_TYPE"0402"
TOLERANCE"1.0%"
VALUE"240"
WATTAGE"1/16W"
PART_NUMBER"G21796-294"
LOCATION"R6D6";
"B"
$PN"2"18;
"A"
$PN"1"3;
%"PVCCIO_CPU0"
"1","(-2975,4550)","0","mstr_symbols","I30";
;
HDL_POWER"PVCCIO_CPU0"
CDS_LIB"mstr_symbols"
BODY_TYPE"PLUMBING"
VOLTAGE"1.1V";
"G\NAC"2;
%"RES"
"1","(-2475,4200)","0","mstr_discrete","I31";
;
CDS_SEC"1"
ROOM"PROC_SIDEBAND"
SEC_TYPE"0402"
SEC"1"
BOM_COST"PROC"
CDS_LIB"mstr_discrete"
CDS_LOCATION"R6D7"
WATTAGE"1/16W"
MATERIAL"EMPTY"
TOLERANCE"1.0%"
PACK_TYPE"0402"
VALUE"240"
PART_NUMBER"G21796-294"
LOCATION"R6D7";
"B"
$PN"2"26;
"A"
$PN"1"2;
%"RES"
"1","(-2475,4000)","0","mstr_discrete","I32";
;
CDS_SEC"1"
ROOM"PROC_SIDEBAND"
SEC_TYPE"0402"
SEC"1"
CDS_LIB"mstr_discrete"
BOM_COST"PROC"
CDS_LOCATION"R5D4"
VALUE"240"
WATTAGE"1/16W"
MATERIAL"EMPTY"
TOLERANCE"1.0%"
PACK_TYPE"0402"
PART_NUMBER"G21796-294"
LOCATION"R5D4";
"B"
$PN"2"29;
"A"
$PN"1"2;
%"RES"
"1","(-2500,3800)","0","mstr_discrete","I33";
;
CDS_SEC"1"
ROOM"PROC_SIDEBAND"
SEC_TYPE"0402"
SEC"1"
CDS_LIB"mstr_discrete"
BOM_COST"PROC"
CDS_LOCATION"R6D13"
PACK_TYPE"0402"
WATTAGE"1/16W"
MATERIAL"EMPTY"
TOLERANCE"1.0%"
VALUE"240"
PART_NUMBER"G21796-294"
LOCATION"R6D13";
"B"
$PN"2"32;
"A"
$PN"1"2;
%"RES"
"1","(-500,3200)","0","mstr_discrete","I4";
;
CDS_SEC"1"
ROOM"PROC_SIDEBAND"
CDS_LIB"mstr_discrete"
BOM_COST"PROC"
SEC_TYPE"0402"
SEC"1"
CDS_LOCATION"R4P1"
MATERIAL"EMPTY"
PACK_TYPE"0402"
TOLERANCE"1.0%"
VALUE"240"
WATTAGE"1/16W"
PART_NUMBER"G21796-294"
LOCATION"R4P1";
"B"
$PN"2"17;
"A"
$PN"1"3;
%"RES"
"1","(-300,4400)","0","mstr_discrete","I48";
;
CDS_SEC"1"
ROOM"PROC_SIDEBAND"
SEC"1"
SEC_TYPE"0402"
CDS_LIB"mstr_discrete"
BOM_COST"PROC"
CDS_LOCATION"R6D15"
WATTAGE"1/16W"
MATERIAL"EMPTY"
TOLERANCE"1.0%"
PACK_TYPE"0402"
VALUE"240"
PART_NUMBER"G21796-294"
LOCATION"R6D15";
"B"
$PN"2"15;
"A"
$PN"1"4;
%"RES"
"1","(-300,4200)","0","mstr_discrete","I49";
;
CDS_SEC"1"
ROOM"PROC_SIDEBAND"
SEC"1"
SEC_TYPE"0402"
CDS_LIB"mstr_discrete"
BOM_COST"PROC"
CDS_LOCATION"R6D10"
WATTAGE"1/16W"
MATERIAL"EMPTY"
TOLERANCE"1.0%"
PACK_TYPE"0402"
VALUE"240"
PART_NUMBER"G21796-294"
LOCATION"R6D10";
"B"
$PN"2"14;
"A"
$PN"1"4;
%"GND"
"1","(-900,2600)","0","mstr_symbols","I5";
;
HDL_POWER"GND"
CDS_LIB"mstr_symbols"
VOLTAGE"0"
BODY_TYPE"PLUMBING"
SIZE"1B";
"A\NAC"3;
%"PVCCIO_CPU0"
"1","(-825,4625)","0","mstr_symbols","I51";
;
CDS_LIB"mstr_symbols"
HDL_POWER"PVCCIO_CPU0"
BODY_TYPE"PLUMBING"
VOLTAGE"1.1V";
"G\NAC"4;
%"RES"
"1","(-2475,3600)","0","mstr_discrete","I52";
;
CDS_SEC"1"
ROOM"PROC_SIDEBAND"
SEC_TYPE"0402"
SEC"1"
BOM_COST"PROC"
CDS_LIB"mstr_discrete"
CDS_LOCATION"R6D14"
WATTAGE"1/16W"
TOLERANCE"1.0%"
VALUE"240"
MATERIAL"EMPTY"
PACK_TYPE"0402"
PART_NUMBER"G21796-294"
LOCATION"R6D14";
"B"
$PN"2"31;
"A"
$PN"1"2;
%"RES"
"1","(-2500,3400)","0","mstr_discrete","I53";
;
CDS_SEC"1"
SEC"1"
SEC_TYPE"0402"
ROOM"PROC_SIDEBAND"
BOM_COST"PROC"
CDS_LIB"mstr_discrete"
CDS_LOCATION"R4P14"
WATTAGE"1/16W"
MATERIAL"CHIP"
TOLERANCE"1.0%"
PACK_TYPE"0402"
VALUE"240"
PART_NUMBER"G21796-294"
LOCATION"R4P14";
"B"
$PN"2"28;
"A"
$PN"1"2;
%"RES"
"1","(-375,1675)","0","mstr_discrete","I59";
;
ROOM"PROC_SIDEBAND"
$SEC"1"
CDS_SEC"1"
BOM_COST"PROC"
CDS_LIB"mstr_discrete"
CDS_LOCATION"R3D24"
WATTAGE"1/16W"
MATERIAL"CHIP"
PACK_TYPE"0402"
TOLERANCE"1.0%"
VALUE"240"
PART_NUMBER"G21796-294"
LOCATION"R3D24";
"B"
$PN"2"19;
"A"
$PN"1"6;
%"RES"
"1","(-350,1475)","0","mstr_discrete","I60";
;
ROOM"PROC_SIDEBAND"
$SEC"1"
CDS_SEC"1"
BOM_COST"PROC"
CDS_LIB"mstr_discrete"
CDS_LOCATION"R3D17"
WATTAGE"1/16W"
MATERIAL"EMPTY"
TOLERANCE"1.0%"
VALUE"240"
PACK_TYPE"0402"
PART_NUMBER"G21796-294"
LOCATION"R3D17";
"B"
$PN"2"20;
"A"
$PN"1"6;
%"PVCCIO_CPU1"
"1","(-2950,2050)","0","mstr_symbols","I62";
;
HDL_POWER"PVCCIO_CPU1"
CDS_LIB"mstr_symbols"
BODY_TYPE"PLUMBING"
VOLTAGE"1.1V";
"G\NAC"5;
%"PVCCIO_CPU1"
"1","(-725,1825)","0","mstr_symbols","I63";
;
CDS_LIB"mstr_symbols"
HDL_POWER"PVCCIO_CPU1"
BODY_TYPE"PLUMBING"
VOLTAGE"1.1V";
"G\NAC"6;
%"RES"
"1","(-2500,1025)","0","mstr_discrete","I66";
;
CDS_SEC"1"
ROOM"PROC_SIDEBAND"
SEC_TYPE"0402"
SEC"1"
BOM_COST"PROC"
CDS_LIB"mstr_discrete"
CDS_LOCATION"R3D25"
WATTAGE"1/16W"
TOLERANCE"1.0%"
VALUE"240"
LOCATION"R3D25"
MATERIAL"EMPTY"
PACK_TYPE"0402"
PART_NUMBER"G21796-294";
"B"
$PN"2"33;
"A"
$PN"1"5;
%"RES"
"1","(-425,3000)","0","mstr_discrete","I68";
;
CDS_SEC"1"
ROOM"PROC_SIDEBAND"
SEC"1"
SEC_TYPE"0402"
CDS_LIB"mstr_discrete"
BOM_COST"PROC"
CDS_LOCATION"R4P6"
WATTAGE"1/16W"
TOLERANCE"1.0%"
VALUE"240"
MATERIAL"EMPTY"
PACK_TYPE"0402"
PART_NUMBER"G21796-294"
LOCATION"R4P6";
"B"
$PN"2"13;
"A"
$PN"1"3;
%"RES"
"1","(-275,850)","0","mstr_discrete","I70";
;
CDS_SEC"1"
ROOM"PROC_SIDEBAND"
SEC"1"
SEC_TYPE"0402"
MATERIAL"CHIP"
BOM_COST"PROC"
CDS_LIB"mstr_discrete"
CDS_LOCATION"R7P14"
WATTAGE"1/16W"
PACK_TYPE"0402"
TOLERANCE"1.0%"
VALUE"240"
PART_NUMBER"G21796-294"
LOCATION"R7P14";
"B"
$PN"2"23;
"A"
$PN"1"1;
%"RES"
"1","(-425,2800)","0","mstr_discrete","I72";
;
CDS_SEC"1"
ROOM"PROC_SIDEBAND"
SEC_TYPE"0402"
SEC"1"
BOM_COST"PROC"
CDS_LIB"mstr_discrete"
CDS_LOCATION"R4P7"
WATTAGE"1/16W"
MATERIAL"EMPTY"
TOLERANCE"1.0%"
PACK_TYPE"0402"
VALUE"240"
PART_NUMBER"G21796-294"
LOCATION"R4P7";
"B"
$PN"2"16;
"A"
$PN"1"3;
%"RES"
"1","(-275,650)","0","mstr_discrete","I74";
;
CDS_SEC"1"
ROOM"PROC_SIDEBAND"
SEC_TYPE"0402"
SEC"1"
BOM_COST"PROC"
CDS_LIB"mstr_discrete"
CDS_LOCATION"R7P15"
MATERIAL"EMPTY"
WATTAGE"1/16W"
PACK_TYPE"0402"
TOLERANCE"1.0%"
VALUE"240"
LOCATION"R7P15"
PART_NUMBER"G21796-294";
"B"
$PN"2"22;
"A"
$PN"1"1;
%"RES"
"1","(-2475,800)","0","mstr_discrete","I76";
;
CDS_SEC"1"
SEC"1"
SEC_TYPE"0402"
ROOM"PROC_SIDEBAND"
BOM_COST"PROC"
CDS_LIB"mstr_discrete"
CDS_LOCATION"R7P22"
WATTAGE"1/16W"
TOLERANCE"1.0%"
VALUE"240"
MATERIAL"EMPTY"
PACK_TYPE"0402"
LOCATION"R7P22"
PART_NUMBER"G21796-294";
"B"
$PN"2"37;
"A"
$PN"1"5;
%"GND"
"1","(-1225,2725)","0","mstr_symbols","I78";
;
HDL_POWER"GND"
BODY_TYPE"PLUMBING"
VOLTAGE"0.0V"
CDS_LIB"mstr_symbols"
SIZE"1B";
"A\NAC"7;
%"RES"
"1","(-1575,3200)","0","mstr_discrete","I79";
;
CDS_SEC"1"
ROOM"CPU0"
SEC"1"
SEC_TYPE"0402"
CDS_LOCATION"R5P2"
CDS_LIB"mstr_discrete"
PART_NUMBER"G21796-047"
TOLERANCE"1%"
LOCATION"R5P2"
VALUE"49.9"
WATTAGE"1/16W"
MATERIAL"CHIP"
PACK_TYPE"0402";
"B"
$PN"2"7;
"A"
$PN"1"30;
%"RES"
"1","(-1575,3075)","0","mstr_discrete","I80";
;
CDS_SEC"1"
ROOM"CPU0"
SEC_TYPE"0402"
SEC"1"
CDS_LOCATION"R5P3"
CDS_LIB"mstr_discrete"
LOCATION"R5P3"
PART_NUMBER"G21796-047"
TOLERANCE"1%"
VALUE"49.9"
WATTAGE"1/16W"
MATERIAL"CHIP"
PACK_TYPE"0402";
"B"
$PN"2"7;
"A"
$PN"1"27;
%"RES"
"1","(-1575,2925)","0","mstr_discrete","I81";
;
CDS_SEC"1"
SEC_TYPE"0402"
SEC"1"
ROOM"CPU0"
CDS_LOCATION"R6D5"
CDS_LIB"mstr_discrete"
PART_NUMBER"G21796-047"
TOLERANCE"1%"
LOCATION"R6D5"
VALUE"49.9"
WATTAGE"1/16W"
MATERIAL"CHIP"
PACK_TYPE"0402";
"B"
$PN"2"7;
"A"
$PN"1"9;
%"RES"
"1","(325,2475)","0","mstr_discrete","I85";
;
CDS_SEC"1"
ROOM"CPU1"
SEC"1"
SEC_TYPE"0402"
CDS_LOCATION"R8P1"
CDS_LIB"mstr_discrete"
PART_NUMBER"G21796-047"
TOLERANCE"1%"
LOCATION"R8P1"
VALUE"49.9"
WATTAGE"1/16W"
MATERIAL"CHIP"
PACK_TYPE"0402";
"B"
$PN"2"8;
"A"
$PN"1"12;
%"RES"
"1","(325,2350)","0","mstr_discrete","I86";
;
CDS_SEC"1"
SEC"1"
SEC_TYPE"0402"
ROOM"CPU1"
CDS_LOCATION"R8P2"
CDS_LIB"mstr_discrete"
PART_NUMBER"G21796-047"
LOCATION"R8P2"
TOLERANCE"1%"
VALUE"49.9"
WATTAGE"1/16W"
MATERIAL"CHIP"
PACK_TYPE"0402";
"B"
$PN"2"8;
"A"
$PN"1"11;
%"GND"
"1","(675,2000)","0","mstr_symbols","I87";
;
HDL_POWER"GND"
BODY_TYPE"PLUMBING"
SIZE"1B"
CDS_LIB"mstr_symbols"
VOLTAGE"0.0V";
"A\NAC"8;
%"RES"
"1","(325,2200)","0","mstr_discrete","I88";
;
CDS_SEC"1"
SEC_TYPE"0402"
ROOM"CPU1"
SEC"1"
CDS_LOCATION"R3D9"
CDS_LIB"mstr_discrete"
PART_NUMBER"G21796-047"
TOLERANCE"1%"
LOCATION"R3D9"
VALUE"49.9"
WATTAGE"1/16W"
MATERIAL"CHIP"
PACK_TYPE"0402";
"B"
$PN"2"8;
"A"
$PN"1"10;
END.
